G04*
G04 #@! TF.GenerationSoftware,Altium Limited,Altium Designer,23.0.1 (38)*
G04*
G04 Layer_Color=16711935*
%FSLAX25Y25*%
%MOIN*%
G70*
G04*
G04 #@! TF.SameCoordinates,C48E81DB-6E20-4E2D-80E6-7C5AFAA1A21F*
G04*
G04*
G04 #@! TF.FilePolarity,Negative*
G04*
G01*
G75*
%ADD144R,0.31496X0.13583*%
%ADD145R,1.35433X0.23032*%
G04:AMPARAMS|DCode=155|XSize=43.31mil|YSize=139.76mil|CornerRadius=21.65mil|HoleSize=0mil|Usage=FLASHONLY|Rotation=90.000|XOffset=0mil|YOffset=0mil|HoleType=Round|Shape=RoundedRectangle|*
%AMROUNDEDRECTD155*
21,1,0.04331,0.09646,0,0,90.0*
21,1,0.00000,0.13976,0,0,90.0*
1,1,0.04331,0.04823,0.00000*
1,1,0.04331,0.04823,0.00000*
1,1,0.04331,-0.04823,0.00000*
1,1,0.04331,-0.04823,0.00000*
%
%ADD155ROUNDEDRECTD155*%
%ADD175R,0.03320X0.03477*%
%ADD207R,0.03600X0.17300*%
%ADD208R,0.03600X0.13400*%
G04:AMPARAMS|DCode=212|XSize=43.31mil|YSize=70.87mil|CornerRadius=21.65mil|HoleSize=0mil|Usage=FLASHONLY|Rotation=90.000|XOffset=0mil|YOffset=0mil|HoleType=Round|Shape=RoundedRectangle|*
%AMROUNDEDRECTD212*
21,1,0.04331,0.02756,0,0,90.0*
21,1,0.00000,0.07087,0,0,90.0*
1,1,0.04331,0.01378,0.00000*
1,1,0.04331,0.01378,0.00000*
1,1,0.04331,-0.01378,0.00000*
1,1,0.04331,-0.01378,0.00000*
%
%ADD212ROUNDEDRECTD212*%
G04:AMPARAMS|DCode=213|XSize=47.24mil|YSize=62.99mil|CornerRadius=23.62mil|HoleSize=0mil|Usage=FLASHONLY|Rotation=90.000|XOffset=0mil|YOffset=0mil|HoleType=Round|Shape=RoundedRectangle|*
%AMROUNDEDRECTD213*
21,1,0.04724,0.01575,0,0,90.0*
21,1,0.00000,0.06299,0,0,90.0*
1,1,0.04724,0.00787,0.00000*
1,1,0.04724,0.00787,0.00000*
1,1,0.04724,-0.00787,0.00000*
1,1,0.04724,-0.00787,0.00000*
%
%ADD213ROUNDEDRECTD213*%
%ADD214C,0.11800*%
%ADD215R,0.10827X0.10827*%
%ADD216C,0.10827*%
%ADD217C,0.00800*%
%ADD218R,0.06902X0.06902*%
%ADD219C,0.06902*%
%ADD220C,0.10800*%
%ADD221C,0.02966*%
%ADD222C,0.24800*%
%ADD223R,0.00800X0.00800*%
%ADD224C,0.07398*%
%ADD225C,0.09461*%
%ADD226R,0.08674X0.08674*%
%ADD227R,0.06706X0.06706*%
%ADD228C,0.06706*%
%ADD229C,0.25800*%
%ADD230C,0.02400*%
%ADD231C,0.05800*%
%ADD232C,0.20800*%
%ADD233C,0.02769*%
D144*
X118504Y-390698D02*
D03*
D145*
X216142Y-404084D02*
D03*
D155*
X692421Y-105610D02*
D03*
Y-72342D02*
D03*
D175*
X273441Y-382293D02*
D03*
Y-378907D02*
D03*
X206441D02*
D03*
Y-382293D02*
D03*
X210441D02*
D03*
Y-378907D02*
D03*
X218341D02*
D03*
Y-382293D02*
D03*
X222641D02*
D03*
Y-378907D02*
D03*
X237941Y-382293D02*
D03*
Y-378907D02*
D03*
X241941Y-382293D02*
D03*
Y-378907D02*
D03*
X253441Y-382293D02*
D03*
Y-378907D02*
D03*
X256941D02*
D03*
Y-382293D02*
D03*
X269441D02*
D03*
Y-378907D02*
D03*
D207*
X281102Y-401427D02*
D03*
X159055D02*
D03*
X155118D02*
D03*
X186614D02*
D03*
X182677D02*
D03*
X241732D02*
D03*
X273228D02*
D03*
X269291D02*
D03*
X257480D02*
D03*
X237795D02*
D03*
X253543D02*
D03*
X222047D02*
D03*
X218110D02*
D03*
X210236D02*
D03*
X206299D02*
D03*
X190551D02*
D03*
X166929D02*
D03*
X170866D02*
D03*
X174803D02*
D03*
X178740D02*
D03*
X229921D02*
D03*
X214173D02*
D03*
X202362D02*
D03*
X249606D02*
D03*
X265354D02*
D03*
X245669D02*
D03*
X277165D02*
D03*
X261417D02*
D03*
X233858D02*
D03*
X225984D02*
D03*
X162992D02*
D03*
D208*
X151181Y-399477D02*
D03*
D212*
X695866Y-105610D02*
D03*
Y-72342D02*
D03*
X688976D02*
D03*
Y-105610D02*
D03*
D213*
X682283Y-74803D02*
D03*
Y-103150D02*
D03*
D214*
X672401Y-135695D02*
D03*
D215*
X643701Y-127445D02*
D03*
D216*
Y-143945D02*
D03*
X622001Y-127445D02*
D03*
Y-143945D02*
D03*
D217*
X640640Y-65206D02*
D03*
Y-17962D02*
D03*
X82785Y-22490D02*
D03*
Y-69734D02*
D03*
X640640Y-33710D02*
D03*
Y-17962D02*
D03*
X82785Y-53986D02*
D03*
Y-69734D02*
D03*
D218*
X181496Y-120079D02*
D03*
D219*
X171496D02*
D03*
X161496D02*
D03*
X151496D02*
D03*
X141496D02*
D03*
D220*
X270472Y-327165D02*
D03*
X282283D02*
D03*
X142520Y-156693D02*
D03*
X294094Y-327165D02*
D03*
X142520Y-316535D02*
D03*
X302362Y-156693D02*
D03*
X142520Y-236614D02*
D03*
X258472Y-327165D02*
D03*
X302362Y-316535D02*
D03*
X246472Y-327165D02*
D03*
X258472D02*
D03*
X282283D02*
D03*
X294094D02*
D03*
X302362Y-156693D02*
D03*
Y-316535D02*
D03*
X142520D02*
D03*
Y-236614D02*
D03*
Y-156693D02*
D03*
X270472Y-327165D02*
D03*
X246472D02*
D03*
D221*
X470275Y-308597D02*
D03*
X391535D02*
D03*
X340904Y-273410D02*
D03*
Y-194670D02*
D03*
X391545Y-160477D02*
D03*
X470285D02*
D03*
X528395Y-194680D02*
D03*
Y-273420D02*
D03*
D222*
X285128Y-308632D02*
D03*
X160020Y-314535D02*
D03*
X162520Y-152693D02*
D03*
X284862Y-164793D02*
D03*
D223*
X533015Y-312764D02*
D03*
X336415Y-155764D02*
D03*
X336515Y-312764D02*
D03*
X533015Y-155764D02*
D03*
D224*
X604291Y-330039D02*
D03*
X574291D02*
D03*
D225*
X-18464Y-326781D02*
D03*
X1535D02*
D03*
Y-306781D02*
D03*
X-18464D02*
D03*
X-18465Y-273630D02*
D03*
X1535D02*
D03*
Y-253630D02*
D03*
X-18465D02*
D03*
Y-220480D02*
D03*
X1535D02*
D03*
Y-200480D02*
D03*
X-18465D02*
D03*
X-18464Y-167332D02*
D03*
X1535D02*
D03*
Y-147332D02*
D03*
X-18464D02*
D03*
D226*
X-8465Y-316781D02*
D03*
X-8465Y-263630D02*
D03*
Y-210480D02*
D03*
X-8465Y-157332D02*
D03*
D227*
X589055Y13937D02*
D03*
D228*
X579055D02*
D03*
X569055D02*
D03*
X559055D02*
D03*
X549055D02*
D03*
X539055D02*
D03*
X589055Y3937D02*
D03*
X579055D02*
D03*
X569055D02*
D03*
X559055D02*
D03*
X549055D02*
D03*
X539055D02*
D03*
D229*
X0Y0D02*
D03*
X0Y-378395D02*
D03*
X685039Y-340551D02*
D03*
X685039Y0D02*
D03*
X486221Y-340551D02*
D03*
D230*
X670538Y-74409D02*
D03*
X668438D02*
D03*
X676772Y-54331D02*
D03*
Y-51575D02*
D03*
X84079Y-105653D02*
D03*
X62986Y-112803D02*
D03*
X62499Y-117255D02*
D03*
X141981Y-347043D02*
D03*
X142520Y-342913D02*
D03*
X198392Y-366842D02*
D03*
X196701Y-370523D02*
D03*
X680709Y-216929D02*
D03*
X671654Y-217323D02*
D03*
X585433Y-114961D02*
D03*
X584252Y-117717D02*
D03*
X679921Y-160236D02*
D03*
X684646Y-161811D02*
D03*
X689370Y-161417D02*
D03*
X689764Y-164567D02*
D03*
Y-168110D02*
D03*
X476945Y-173228D02*
D03*
X555512Y-218504D02*
D03*
X474016Y-176378D02*
D03*
X460186Y-175448D02*
D03*
X578168Y-80778D02*
D03*
X530027Y-172987D02*
D03*
X533044Y-176225D02*
D03*
X495669Y-222047D02*
D03*
X500394Y-222835D02*
D03*
X644488Y-170472D02*
D03*
X644619Y-166285D02*
D03*
X644569Y-162910D02*
D03*
X644488Y-159843D02*
D03*
X435827Y-103543D02*
D03*
X402719Y-112334D02*
D03*
X409900Y-136559D02*
D03*
X430492Y-136473D02*
D03*
X414567Y-137402D02*
D03*
X436614Y-136614D02*
D03*
X443307Y-111024D02*
D03*
X664966Y-316582D02*
D03*
X664961Y-325984D02*
D03*
X692037Y-315878D02*
D03*
X692126Y-322441D02*
D03*
X256897Y-112001D02*
D03*
X255118Y-118504D02*
D03*
X254376Y-125747D02*
D03*
X241250Y-126247D02*
D03*
X238189Y-116142D02*
D03*
X246063Y-111024D02*
D03*
X248425Y-129134D02*
D03*
X241077Y-118805D02*
D03*
X255512Y-121260D02*
D03*
X253713Y-109190D02*
D03*
X253690Y-111960D02*
D03*
X244664Y-106952D02*
D03*
X228824Y-104850D02*
D03*
X577953Y-83858D02*
D03*
X618898Y-82284D02*
D03*
X612205Y-87008D02*
D03*
X609055Y-92520D02*
D03*
X620959Y-100047D02*
D03*
X612598Y-100000D02*
D03*
X629134Y-102756D02*
D03*
X631814Y-83784D02*
D03*
X629101Y-90137D02*
D03*
X623228Y-93307D02*
D03*
X616535Y-84646D02*
D03*
X616929Y-100000D02*
D03*
X599279Y-82981D02*
D03*
X597227Y-77103D02*
D03*
X601745Y-98051D02*
D03*
X588372Y-100945D02*
D03*
X567323Y-94095D02*
D03*
X569291Y-91339D02*
D03*
X568504Y-88189D02*
D03*
X579921Y-101969D02*
D03*
X584763Y-100116D02*
D03*
X588976Y-86221D02*
D03*
X600394Y-87795D02*
D03*
X592520Y-93307D02*
D03*
X666929Y-98032D02*
D03*
X662539Y-107066D02*
D03*
X667717Y-106693D02*
D03*
X696762Y-63288D02*
D03*
X696577Y-51453D02*
D03*
X675591Y-42520D02*
D03*
X685716Y-22157D02*
D03*
X679517Y-26553D02*
D03*
Y-37023D02*
D03*
X693915Y-33393D02*
D03*
X686728Y-33442D02*
D03*
X686319Y-43553D02*
D03*
X683127Y-66209D02*
D03*
X689466Y-66165D02*
D03*
X680082Y-64183D02*
D03*
X675926Y-72691D02*
D03*
X660719Y-75726D02*
D03*
X694095Y-62205D02*
D03*
X693977Y-53201D02*
D03*
X676378Y-83858D02*
D03*
X538583Y-111811D02*
D03*
X539233Y-115729D02*
D03*
X569092Y-108048D02*
D03*
X546386Y-109024D02*
D03*
X548093Y-185219D02*
D03*
X548425Y-181890D02*
D03*
X548819Y-178740D02*
D03*
X547244Y-157087D02*
D03*
Y-144488D02*
D03*
X524409Y-135827D02*
D03*
X531801Y-127495D02*
D03*
X539900Y-140766D02*
D03*
X570472Y-137795D02*
D03*
X579921Y-133465D02*
D03*
X574409D02*
D03*
X570866D02*
D03*
X572047Y-129921D02*
D03*
X576378D02*
D03*
X580315D02*
D03*
X646457Y-156693D02*
D03*
X642520D02*
D03*
X635039Y-216142D02*
D03*
X608661Y-236221D02*
D03*
X572441Y-227165D02*
D03*
X678441Y-292586D02*
D03*
X678346Y-297244D02*
D03*
X639764Y-283858D02*
D03*
X554724Y-294882D02*
D03*
X565354Y-292913D02*
D03*
X630577Y-278001D02*
D03*
X582874Y-294291D02*
D03*
X680709Y-212205D02*
D03*
X673622Y-213779D02*
D03*
X669685D02*
D03*
X666142Y-212992D02*
D03*
X599564Y-178940D02*
D03*
X594882Y-179134D02*
D03*
X589764D02*
D03*
X584646Y-178740D02*
D03*
X635827Y-187795D02*
D03*
X635433Y-184252D02*
D03*
X652756Y-164961D02*
D03*
X657480Y-164567D02*
D03*
X662992Y-164961D02*
D03*
X668504D02*
D03*
X681496Y-179528D02*
D03*
X677165Y-172441D02*
D03*
X673228D02*
D03*
X675197Y-200000D02*
D03*
X678740D02*
D03*
X681890D02*
D03*
Y-196850D02*
D03*
X678740D02*
D03*
X675591Y-196457D02*
D03*
X652756Y-218504D02*
D03*
X650000Y-231102D02*
D03*
X646434Y-231245D02*
D03*
X598425Y-198819D02*
D03*
X595276D02*
D03*
X592126D02*
D03*
X589764D02*
D03*
X587008D02*
D03*
X570079Y-200000D02*
D03*
X549298Y-191988D02*
D03*
X600000Y-248425D02*
D03*
X616535Y-255512D02*
D03*
X612205Y-251575D02*
D03*
X624803Y-255906D02*
D03*
Y-251575D02*
D03*
X624409Y-248031D02*
D03*
X611417Y-247638D02*
D03*
X605118Y-244488D02*
D03*
X673228Y-251181D02*
D03*
X672835Y-257087D02*
D03*
X673622Y-261417D02*
D03*
X676378Y-266142D02*
D03*
X676772Y-270866D02*
D03*
X671260Y-274803D02*
D03*
Y-278740D02*
D03*
X671654Y-283071D02*
D03*
X683858Y-310630D02*
D03*
X683716Y-298538D02*
D03*
X651575Y-275197D02*
D03*
X648819Y-278740D02*
D03*
X652362Y-279528D02*
D03*
X657087D02*
D03*
X654331Y-283858D02*
D03*
X650000D02*
D03*
X646457D02*
D03*
X637795Y-297638D02*
D03*
X585039Y-249606D02*
D03*
X590551Y-266535D02*
D03*
X588189Y-263386D02*
D03*
X585433Y-253937D02*
D03*
Y-257480D02*
D03*
X581496D02*
D03*
X577953D02*
D03*
X559842Y-257087D02*
D03*
X579134Y-195276D02*
D03*
X574803D02*
D03*
X577953Y-198819D02*
D03*
X590158Y-226378D02*
D03*
X586221Y-226772D02*
D03*
X579921Y-227559D02*
D03*
X576772Y-228740D02*
D03*
X637008Y-238583D02*
D03*
X608661Y-242126D02*
D03*
X590551Y-242520D02*
D03*
X586537Y-234843D02*
D03*
X546850Y-213779D02*
D03*
X548819Y-196063D02*
D03*
X547244Y-203150D02*
D03*
X554724Y-207874D02*
D03*
X549213D02*
D03*
X569291Y-194095D02*
D03*
X581496Y-198819D02*
D03*
X573622D02*
D03*
X571162Y-284136D02*
D03*
X577953Y-284646D02*
D03*
X574803Y-284252D02*
D03*
X568110D02*
D03*
X567717Y-259055D02*
D03*
X566535Y-255906D02*
D03*
X570079D02*
D03*
X548425Y-253543D02*
D03*
X545669Y-253937D02*
D03*
X545128Y-280872D02*
D03*
X544909Y-287437D02*
D03*
X545276Y-294094D02*
D03*
Y-275197D02*
D03*
Y-270866D02*
D03*
X544488Y-265748D02*
D03*
X557087Y-261417D02*
D03*
X556628Y-258042D02*
D03*
X569548Y-287223D02*
D03*
X595276Y-291732D02*
D03*
X612598D02*
D03*
X627559Y-296457D02*
D03*
X563386Y-257874D02*
D03*
X572441Y-258268D02*
D03*
X475984Y-127165D02*
D03*
X480120Y-132365D02*
D03*
X469685Y-133465D02*
D03*
X473228Y-105905D02*
D03*
X488583Y-132283D02*
D03*
X506299Y-129921D02*
D03*
X498032Y-132283D02*
D03*
X506207Y-127333D02*
D03*
X505905Y-123622D02*
D03*
X472441Y-113779D02*
D03*
X483484Y-105840D02*
D03*
X504703Y-106672D02*
D03*
X508268Y-117323D02*
D03*
X501669Y-116601D02*
D03*
X500313Y-105734D02*
D03*
X476772Y-123622D02*
D03*
X518337Y-159634D02*
D03*
X515702Y-162803D02*
D03*
X498693Y-188351D02*
D03*
X498819Y-183858D02*
D03*
X499111Y-179528D02*
D03*
X658114Y-56714D02*
D03*
X657445Y-63525D02*
D03*
X658053Y-71188D02*
D03*
X623511Y-62552D02*
D03*
X623228Y-55118D02*
D03*
X423461Y-178869D02*
D03*
X144871Y-131609D02*
D03*
X314417Y-228033D02*
D03*
X314623Y-231391D02*
D03*
X416835Y-196581D02*
D03*
X411811Y-196850D02*
D03*
X314658Y-244775D02*
D03*
X315097Y-235081D02*
D03*
X314503Y-225180D02*
D03*
D231*
X348211Y-89891D02*
D03*
X357798Y-89963D02*
D03*
D232*
X651545Y-95108D02*
D03*
X413356Y7254D02*
D03*
Y-95108D02*
D03*
X651545Y7254D02*
D03*
X71880Y7412D02*
D03*
X310069Y-94950D02*
D03*
Y7412D02*
D03*
X71880Y-94950D02*
D03*
D233*
X99016Y-121653D02*
D03*
X103347D02*
D03*
X107677D02*
D03*
X99016Y-125984D02*
D03*
X103347D02*
D03*
X107677D02*
D03*
X99016Y-130315D02*
D03*
X103347D02*
D03*
X107677D02*
D03*
M02*
